(kicad_pcb
	(version 20260206)
	(generator "pcbnew")
	(generator_version "10.0")
	(general
		(thickness 1.6)
		(legacy_teardrops no)
	)
	(paper "A4")
	(title_block
		(title "dpb — 14545-sa.0730WZS0815.brd")
		(comment 1 "Honey Badger (Wiwynn) / footprints 693-700 of 1066")
	)
	(layers
		(0 "F.Cu" signal "TOP")
		(4 "In1.Cu" signal "L2GND")
		(6 "In2.Cu" signal "L3")
		(8 "In3.Cu" signal "L4VCC")
		(10 "In4.Cu" signal "L5VCC")
		(12 "In5.Cu" signal "L6")
		(14 "In6.Cu" signal "L7GND")
		(2 "B.Cu" signal "BOTTOM")
		(9 "F.Adhes" user "F.Adhesive")
		(11 "B.Adhes" user "B.Adhesive")
		(13 "F.Paste" user "Package Geometry/Pastemask Top")
		(15 "B.Paste" user "Package Geometry/Pastemask Bottom")
		(5 "F.SilkS" user "Ref Des/Silkscreen Top")
		(7 "B.SilkS" user "Ref Des/Silkscreen Bottom")
		(1 "F.Mask" user "Board Geometry/Soldermask Top")
		(3 "B.Mask" user "Board Geometry/Soldermask Bottom")
		(17 "Dwgs.User" user "User.Drawings")
		(19 "Cmts.User" user "User.Comments")
		(21 "Eco1.User" user "User.Eco1")
		(23 "Eco2.User" user "User.Eco2")
		(25 "Edge.Cuts" user "Board Geometry/Outline")
		(27 "Margin" user)
		(31 "F.CrtYd" user "Package Geometry/Place Bound Top")
		(29 "B.CrtYd" user "Package Geometry/Place Bound Bottom")
		(35 "F.Fab" user "Ref Des/Assembly Top")
		(33 "B.Fab" user "Ref Des/Assembly Bottom")
	)
	(footprint ""
		(layer "F.Cu")
		(at 35.305746 -131.854702 180)
		(property "Reference" "C323"
			(at 0 0 180)
			(layer "F.SilkS")
			(hide yes)
			(effects
				(font
					(size 1.27 1.27)
				)
			)
		)
		(property "Value" "SCD01U50V2KX-1GP"
			(at 1.1811 -2.7051 180)
			(unlocked yes)
			(layer "F.Fab")
			(hide yes)
			(effects
				(font
					(size 1.016 1.016)
					(thickness 0.1524)
				)
			)
		)
		(property "Device Type" "C402H22"
			(at 1.1811 -4.2291 180)
			(unlocked yes)
			(layer "F.Fab")
			(hide yes)
			(effects
				(font
					(size 1.016 1.016)
					(thickness 0.1524)
				)
			)
		)
		(duplicate_pad_numbers_are_jumpers no)
		(fp_rect
			(start -0.4318 0.9525)
			(end 0.4318 -0.9525)
			(stroke
				(width 0)
				(type default)
			)
			(fill no)
			(layer "F.CrtYd")
		)
		(fp_rect
			(start -0.4318 0.9525)
			(end 0.4318 -0.9525)
			(stroke
				(width 0)
				(type default)
			)
			(fill no)
			(layer "F.Fab")
		)
		(pad "1" smd custom
			(at 0 -0.4445 180)
			(size 0.1524 0.1524)
			(layers "F.Cu" "F.Mask" "F.Paste")
			(net "HDD_PRSNT_NET13")
			(options
				(clearance outline)
				(anchor circle)
			)
			(primitives
				(gr_poly
					(pts
						(arc
							(start 0.3048 -0.2032)
							(mid 0.275042 -0.275042)
							(end 0.2032 -0.3048)
						)
						(arc
							(start -0.2032 -0.3048)
							(mid -0.275042 -0.275042)
							(end -0.3048 -0.2032)
						)
						(arc
							(start -0.3048 0.2032)
							(mid -0.275042 0.275042)
							(end -0.2032 0.3048)
						)
						(arc
							(start 0.2032 0.3048)
							(mid 0.275042 0.275042)
							(end 0.3048 0.2032)
						)
					)
					(width 0)
					(fill yes)
				)
			)
		)
		(pad "2" smd custom
			(at 0 0.4445 180)
			(size 0.1524 0.1524)
			(layers "F.Cu" "F.Mask" "F.Paste")
			(net "GND")
			(options
				(clearance outline)
				(anchor circle)
			)
			(primitives
				(gr_poly
					(pts
						(arc
							(start 0.3048 -0.2032)
							(mid 0.275042 -0.275042)
							(end 0.2032 -0.3048)
						)
						(arc
							(start -0.2032 -0.3048)
							(mid -0.275042 -0.275042)
							(end -0.3048 -0.2032)
						)
						(arc
							(start -0.3048 0.2032)
							(mid -0.275042 0.275042)
							(end -0.2032 0.3048)
						)
						(arc
							(start 0.2032 0.3048)
							(mid 0.275042 0.275042)
							(end 0.3048 0.2032)
						)
					)
					(width 0)
					(fill yes)
				)
			)
		)
	)
	(footprint ""
		(layer "F.Cu")
		(at 47.751746 -217.706702)
		(property "Reference" "C304"
			(at 0 0 0)
			(layer "F.SilkS")
			(hide yes)
			(effects
				(font
					(size 1.27 1.27)
				)
			)
		)
		(property "Value" "SC10U25V6KX-1GP"
			(at -0.0762 -5.1308 0)
			(unlocked yes)
			(layer "F.Fab")
			(hide yes)
			(effects
				(font
					(size 1.016 1.016)
					(thickness 0.1524)
				)
			)
		)
		(property "Device Type" "C1206H71"
			(at -0.127 -6.6548 0)
			(unlocked yes)
			(layer "F.Fab")
			(hide yes)
			(effects
				(font
					(size 1.016 1.016)
					(thickness 0.1524)
				)
			)
		)
		(duplicate_pad_numbers_are_jumpers no)
		(fp_line
			(start -1.016 -2.2352)
			(end 1.016 -2.2352)
			(stroke
				(width 0.1524)
				(type default)
			)
			(layer "F.SilkS")
		)
		(fp_line
			(start -1.016 -0.8382)
			(end -1.016 -2.2352)
			(stroke
				(width 0.1524)
				(type default)
			)
			(layer "F.SilkS")
		)
		(fp_line
			(start -1.016 2.2352)
			(end -1.016 0.8382)
			(stroke
				(width 0.1524)
				(type default)
			)
			(layer "F.SilkS")
		)
		(fp_line
			(start 1.016 -2.2352)
			(end 1.016 -0.8382)
			(stroke
				(width 0.1524)
				(type default)
			)
			(layer "F.SilkS")
		)
		(fp_line
			(start 1.016 0.8382)
			(end 1.016 2.2352)
			(stroke
				(width 0.1524)
				(type default)
			)
			(layer "F.SilkS")
		)
		(fp_line
			(start 1.016 2.2352)
			(end -1.016 2.2352)
			(stroke
				(width 0.1524)
				(type default)
			)
			(layer "F.SilkS")
		)
		(fp_rect
			(start -1.0922 2.3114)
			(end 1.0922 -2.3114)
			(stroke
				(width 0)
				(type default)
			)
			(fill no)
			(layer "F.CrtYd")
		)
		(fp_poly
			(pts
				(xy 1.0922 -2.3114) (xy 1.0922 2.3114) (xy -1.0922 2.3114) (xy -1.0922 -2.3114)
			)
			(stroke
				(width 0)
				(type default)
			)
			(fill no)
			(layer "F.Fab")
		)
		(pad "1" smd rect
			(at 0 -1.397)
			(size 1.651 1.27)
			(layers "F.Cu" "F.Mask" "F.Paste")
			(net "P12V_HDD12")
		)
		(pad "2" smd rect
			(at 0 1.397)
			(size 1.651 1.27)
			(layers "F.Cu" "F.Mask" "F.Paste")
			(net "GND")
		)
	)
	(footprint ""
		(layer "F.Cu")
		(at 207.4164 -272.5166 -90)
		(property "Reference" "Q33"
			(at 0 0 270)
			(layer "F.SilkS")
			(hide yes)
			(effects
				(font
					(size 1.27 1.27)
				)
			)
		)
		(property "Value" "2N7002DW-7F-GP"
			(at -2.3622 -8.2042 270)
			(unlocked yes)
			(layer "F.Fab")
			(hide yes)
			(effects
				(font
					(size 1.016 1.016)
					(thickness 0.1524)
				)
			)
		)
		(property "Device Type" "SOT-363H44"
			(at -2.3622 -10.1092 270)
			(unlocked yes)
			(layer "F.Fab")
			(hide yes)
			(effects
				(font
					(size 1.016 1.016)
					(thickness 0.1524)
				)
			)
		)
		(duplicate_pad_numbers_are_jumpers no)
		(fp_line
			(start -1.4478 1.7018)
			(end 1.4478 1.7018)
			(stroke
				(width 0.1524)
				(type default)
			)
			(layer "F.SilkS")
		)
		(fp_line
			(start 1.4478 1.7018)
			(end 1.4478 -1.7018)
			(stroke
				(width 0.1524)
				(type default)
			)
			(layer "F.SilkS")
		)
		(fp_line
			(start -1.27 1.524)
			(end -1.27 0.6604)
			(stroke
				(width 0.4826)
				(type default)
			)
			(layer "F.SilkS")
		)
		(fp_line
			(start -1.4478 -1.7018)
			(end -1.4478 1.7018)
			(stroke
				(width 0.1524)
				(type default)
			)
			(layer "F.SilkS")
		)
		(fp_line
			(start 1.4478 -1.7018)
			(end -1.4478 -1.7018)
			(stroke
				(width 0.1524)
				(type default)
			)
			(layer "F.SilkS")
		)
		(fp_poly
			(pts
				(xy -1.524 -1.778) (xy 1.524 -1.778) (xy 1.524 1.778) (xy -1.524 1.778)
			)
			(stroke
				(width 0)
				(type default)
			)
			(fill no)
			(layer "F.CrtYd")
		)
		(fp_poly
			(pts
				(xy -1.524 -1.778) (xy 1.524 -1.778) (xy 1.524 1.778) (xy -1.524 1.778)
			)
			(stroke
				(width 0)
				(type default)
			)
			(fill no)
			(layer "F.Fab")
		)
		(pad "1" smd rect
			(at -0.65024 0.9398 270)
			(size 0.4064 1.016)
			(layers "F.Cu" "F.Mask" "F.Paste")
			(net "P3V3_HDD2_LED")
		)
		(pad "2" smd rect
			(at 0 0.9398 270)
			(size 0.4064 1.016)
			(layers "F.Cu" "F.Mask" "F.Paste")
			(net "HDD2_LED_G")
		)
		(pad "3" smd rect
			(at 0.65024 0.9398 270)
			(size 0.4064 1.016)
			(layers "F.Cu" "F.Mask" "F.Paste")
			(net "P5VA")
		)
		(pad "4" smd rect
			(at 0.65024 -0.9398 270)
			(size 0.4064 1.016)
			(layers "F.Cu" "F.Mask" "F.Paste")
			(net "P5VA_HDD2_LED")
		)
		(pad "5" smd rect
			(at 0 -0.9398 270)
			(size 0.4064 1.016)
			(layers "F.Cu" "F.Mask" "F.Paste")
			(net "HDD2_LED_G")
		)
		(pad "6" smd rect
			(at -0.65024 -0.9398 270)
			(size 0.4064 1.016)
			(layers "F.Cu" "F.Mask" "F.Paste")
			(net "P3V3")
		)
	)
	(footprint ""
		(layer "F.Cu")
		(at 36.237418 -332.29804 180)
		(property "Reference" "C283"
			(at 0 0 180)
			(layer "F.SilkS")
			(hide yes)
			(effects
				(font
					(size 1.27 1.27)
				)
			)
		)
		(property "Value" "SCD1U10V2KX-5GP"
			(at 1.1811 -2.7051 180)
			(unlocked yes)
			(layer "F.Fab")
			(hide yes)
			(effects
				(font
					(size 1.016 1.016)
					(thickness 0.1524)
				)
			)
		)
		(property "Device Type" "C402H22"
			(at 1.1811 -4.2291 180)
			(unlocked yes)
			(layer "F.Fab")
			(hide yes)
			(effects
				(font
					(size 1.016 1.016)
					(thickness 0.1524)
				)
			)
		)
		(duplicate_pad_numbers_are_jumpers no)
		(fp_rect
			(start -0.4318 0.9525)
			(end 0.4318 -0.9525)
			(stroke
				(width 0)
				(type default)
			)
			(fill no)
			(layer "F.CrtYd")
		)
		(fp_rect
			(start -0.4318 0.9525)
			(end 0.4318 -0.9525)
			(stroke
				(width 0)
				(type default)
			)
			(fill no)
			(layer "F.Fab")
		)
		(pad "1" smd custom
			(at 0 -0.4445 180)
			(size 0.1524 0.1524)
			(layers "F.Cu" "F.Mask" "F.Paste")
			(net "P3V3")
			(options
				(clearance outline)
				(anchor circle)
			)
			(primitives
				(gr_poly
					(pts
						(arc
							(start 0.3048 -0.2032)
							(mid 0.275042 -0.275042)
							(end 0.2032 -0.3048)
						)
						(arc
							(start -0.2032 -0.3048)
							(mid -0.275042 -0.275042)
							(end -0.3048 -0.2032)
						)
						(arc
							(start -0.3048 0.2032)
							(mid -0.275042 0.275042)
							(end -0.2032 0.3048)
						)
						(arc
							(start 0.2032 0.3048)
							(mid 0.275042 0.275042)
							(end 0.3048 0.2032)
						)
					)
					(width 0)
					(fill yes)
				)
			)
		)
		(pad "2" smd custom
			(at 0 0.4445 180)
			(size 0.1524 0.1524)
			(layers "F.Cu" "F.Mask" "F.Paste")
			(net "GND")
			(options
				(clearance outline)
				(anchor circle)
			)
			(primitives
				(gr_poly
					(pts
						(arc
							(start 0.3048 -0.2032)
							(mid 0.275042 -0.275042)
							(end 0.2032 -0.3048)
						)
						(arc
							(start -0.2032 -0.3048)
							(mid -0.275042 -0.275042)
							(end -0.3048 -0.2032)
						)
						(arc
							(start -0.3048 0.2032)
							(mid -0.275042 0.275042)
							(end -0.2032 0.3048)
						)
						(arc
							(start 0.2032 0.3048)
							(mid 0.275042 0.275042)
							(end 0.3048 0.2032)
						)
					)
					(width 0)
					(fill yes)
				)
			)
		)
	)
	(footprint ""
		(layer "F.Cu")
		(at 194.774058 -389.584184 -90)
		(property "Reference" "U6"
			(at 0 0 270)
			(layer "F.SilkS")
			(hide yes)
			(effects
				(font
					(size 1.27 1.27)
				)
			)
		)
		(property "Value" "74LVC1G08GW-1-GP"
			(at -2.3368 -8.6868 270)
			(unlocked yes)
			(layer "F.Fab")
			(hide yes)
			(effects
				(font
					(size 1.016 1.016)
					(thickness 0.1524)
				)
			)
		)
		(property "Device Type" "SC70-5H44"
			(at -2.3114 -10.414 270)
			(unlocked yes)
			(layer "F.Fab")
			(hide yes)
			(effects
				(font
					(size 1.016 1.016)
					(thickness 0.1524)
				)
			)
		)
		(duplicate_pad_numbers_are_jumpers no)
		(fp_line
			(start -1.27 1.7018)
			(end -1.27 -1.7018)
			(stroke
				(width 0.1524)
				(type default)
			)
			(layer "F.SilkS")
		)
		(fp_line
			(start 1.27 1.7018)
			(end -1.27 1.7018)
			(stroke
				(width 0.1524)
				(type default)
			)
			(layer "F.SilkS")
		)
		(fp_line
			(start -1.27 -1.7018)
			(end 1.27 -1.7018)
			(stroke
				(width 0.1524)
				(type default)
			)
			(layer "F.SilkS")
		)
		(fp_line
			(start 1.27 -1.7018)
			(end 1.27 1.7018)
			(stroke
				(width 0.1524)
				(type default)
			)
			(layer "F.SilkS")
		)
		(fp_line
			(start 0.6604 -1.8034)
			(end 1.3843 -1.8034)
			(stroke
				(width 0.3302)
				(type default)
			)
			(layer "F.SilkS")
		)
		(fp_line
			(start 1.3843 -1.8034)
			(end 1.3843 -1.1176)
			(stroke
				(width 0.3302)
				(type default)
			)
			(layer "F.SilkS")
		)
		(fp_rect
			(start -1.524 1.9558)
			(end 1.524 -1.9558)
			(stroke
				(width 0)
				(type default)
			)
			(fill no)
			(layer "F.CrtYd")
		)
		(fp_poly
			(pts
				(xy -1.524 -1.9558) (xy 1.524 -1.9558) (xy 1.524 1.9558) (xy -1.524 1.9558)
			)
			(stroke
				(width 0)
				(type default)
			)
			(fill no)
			(layer "F.Fab")
		)
		(pad "1" smd rect
			(at 0.65024 -0.8255 270)
			(size 0.4064 1.2192)
			(layers "F.Cu" "F.Mask" "F.Paste")
			(net "SAS_EXP_B_PWR1")
		)
		(pad "2" smd rect
			(at 0 -0.8255 270)
			(size 0.4064 1.2192)
			(layers "F.Cu" "F.Mask" "F.Paste")
			(net "SAS_EXP_A_PWR1")
		)
		(pad "3" smd rect
			(at -0.65024 -0.8255 270)
			(size 0.4064 1.2192)
			(layers "F.Cu" "F.Mask" "F.Paste")
			(net "GND")
		)
		(pad "4" smd rect
			(at -0.65024 0.8255 270)
			(size 0.4064 1.2192)
			(layers "F.Cu" "F.Mask" "F.Paste")
			(net "DRIVE_PWR1")
		)
		(pad "5" smd rect
			(at 0.65024 0.8255 270)
			(size 0.4064 1.2192)
			(layers "F.Cu" "F.Mask" "F.Paste")
			(net "P3V3")
		)
	)
	(footprint ""
		(layer "F.Cu")
		(at 45.338746 -39.7637 90)
		(property "Reference" "R230"
			(at 0 0 90)
			(layer "F.SilkS")
			(hide yes)
			(effects
				(font
					(size 1.27 1.27)
				)
			)
		)
		(property "Value" "0R2J-2-GP"
			(at 0.064008 -3.993896 90)
			(unlocked yes)
			(layer "F.Fab")
			(hide yes)
			(effects
				(font
					(size 1.016 1.016)
					(thickness 0.1524)
				)
			)
		)
		(property "Device Type" "R402H16"
			(at 0.064008 -5.517896 90)
			(unlocked yes)
			(layer "F.Fab")
			(hide yes)
			(effects
				(font
					(size 1.016 1.016)
					(thickness 0.1524)
				)
			)
		)
		(duplicate_pad_numbers_are_jumpers no)
		(fp_line
			(start 0.508 -0.9398)
			(end -0.508 -0.9398)
			(stroke
				(width 0.1524)
				(type default)
			)
			(layer "F.SilkS")
		)
		(fp_line
			(start -0.508 -0.9398)
			(end -0.508 0.9398)
			(stroke
				(width 0.1524)
				(type default)
			)
			(layer "F.SilkS")
		)
		(fp_rect
			(start -0.508 0.9398)
			(end 0.508 -0.9398)
			(stroke
				(width 0)
				(type default)
			)
			(fill no)
			(layer "F.CrtYd")
		)
		(fp_rect
			(start -0.508 0.9398)
			(end 0.508 -0.9398)
			(stroke
				(width 0)
				(type default)
			)
			(fill no)
			(layer "F.Fab")
		)
		(pad "1" smd custom
			(at 0 -0.4445 90)
			(size 0.1397 0.1397)
			(layers "F.Cu" "F.Mask" "F.Paste")
			(net "FLT_NET_HDD9")
			(options
				(clearance outline)
				(anchor circle)
			)
			(primitives
				(gr_poly
					(pts
						(arc
							(start -0.1778 -0.2794)
							(mid -0.249642 -0.249642)
							(end -0.2794 -0.1778)
						)
						(arc
							(start -0.2794 0.1778)
							(mid -0.249642 0.249642)
							(end -0.1778 0.2794)
						)
						(arc
							(start 0.1778 0.2794)
							(mid 0.249642 0.249642)
							(end 0.2794 0.1778)
						)
						(arc
							(start 0.2794 -0.1778)
							(mid 0.249642 -0.249642)
							(end 0.1778 -0.2794)
						)
					)
					(width 0)
					(fill yes)
				)
			)
		)
		(pad "2" smd custom
			(at 0 0.4445 90)
			(size 0.1397 0.1397)
			(layers "F.Cu" "F.Mask" "F.Paste")
			(net "FLT_HDD9_DRIVE")
			(options
				(clearance outline)
				(anchor circle)
			)
			(primitives
				(gr_poly
					(pts
						(arc
							(start -0.1778 -0.2794)
							(mid -0.249642 -0.249642)
							(end -0.2794 -0.1778)
						)
						(arc
							(start -0.2794 0.1778)
							(mid -0.249642 0.249642)
							(end -0.1778 0.2794)
						)
						(arc
							(start 0.1778 0.2794)
							(mid 0.249642 0.249642)
							(end 0.2794 0.1778)
						)
						(arc
							(start 0.2794 -0.1778)
							(mid 0.249642 -0.249642)
							(end 0.1778 -0.2794)
						)
					)
					(width 0)
					(fill yes)
				)
			)
		)
	)
	(footprint ""
		(layer "F.Cu")
		(at 58.165746 -178.5747 90)
		(property "Reference" "R218"
			(at 0 0 90)
			(layer "F.SilkS")
			(hide yes)
			(effects
				(font
					(size 1.27 1.27)
				)
			)
		)
		(property "Value" "2R2010J-1-GP"
			(at 0.254 -8.0772 90)
			(unlocked yes)
			(layer "F.Fab")
			(hide yes)
			(effects
				(font
					(size 1.016 1.016)
					(thickness 0.1524)
				)
			)
		)
		(property "Device Type" "R2010H28"
			(at 0.254 -9.6774 90)
			(unlocked yes)
			(layer "F.Fab")
			(hide yes)
			(effects
				(font
					(size 1.016 1.016)
					(thickness 0.1524)
				)
			)
		)
		(duplicate_pad_numbers_are_jumpers no)
		(fp_line
			(start 1.651 -3.302)
			(end -1.651 -3.302)
			(stroke
				(width 0.1524)
				(type default)
			)
			(layer "F.SilkS")
		)
		(fp_line
			(start -1.651 -3.302)
			(end -1.651 3.302)
			(stroke
				(width 0.1524)
				(type default)
			)
			(layer "F.SilkS")
		)
		(fp_line
			(start 1.651 3.302)
			(end 1.651 -3.302)
			(stroke
				(width 0.1524)
				(type default)
			)
			(layer "F.SilkS")
		)
		(fp_line
			(start -1.651 3.302)
			(end 1.651 3.302)
			(stroke
				(width 0.1524)
				(type default)
			)
			(layer "F.SilkS")
		)
		(fp_rect
			(start -1.7272 -3.3782)
			(end 1.7272 3.3782)
			(stroke
				(width 0)
				(type default)
			)
			(fill no)
			(layer "F.CrtYd")
		)
		(fp_poly
			(pts
				(xy 1.7272 3.3782) (xy 1.7272 -3.3782) (xy -1.7272 -3.3782) (xy -1.7272 3.3782)
			)
			(stroke
				(width 0)
				(type default)
			)
			(fill no)
			(layer "F.Fab")
		)
		(pad "1" smd rect
			(at 0 -2.3495 90)
			(size 2.794 1.143)
			(layers "F.Cu" "F.Mask" "F.Paste")
			(net "5V_PRE_8")
		)
		(pad "2" smd rect
			(at 0 2.3495 90)
			(size 2.794 1.143)
			(layers "F.Cu" "F.Mask" "F.Paste")
			(net "P5V_HDD8")
		)
	)
	(footprint ""
		(layer "F.Cu")
		(at 45.482256 -453.799702 90)
		(property "Reference" "R170"
			(at 0 0 90)
			(layer "F.SilkS")
			(hide yes)
			(effects
				(font
					(size 1.27 1.27)
				)
			)
		)
		(property "Value" "10KR2F-2-GP"
			(at 0.064008 -3.993896 90)
			(unlocked yes)
			(layer "F.Fab")
			(hide yes)
			(effects
				(font
					(size 1.016 1.016)
					(thickness 0.1524)
				)
			)
		)
		(property "Device Type" "R402H16"
			(at 0.064008 -5.517896 90)
			(unlocked yes)
			(layer "F.Fab")
			(hide yes)
			(effects
				(font
					(size 1.016 1.016)
					(thickness 0.1524)
				)
			)
		)
		(duplicate_pad_numbers_are_jumpers no)
		(fp_line
			(start 0.508 -0.9398)
			(end -0.508 -0.9398)
			(stroke
				(width 0.1524)
				(type default)
			)
			(layer "F.SilkS")
		)
		(fp_line
			(start -0.508 -0.9398)
			(end -0.508 0.9398)
			(stroke
				(width 0.1524)
				(type default)
			)
			(layer "F.SilkS")
		)
		(fp_rect
			(start -0.508 0.9398)
			(end 0.508 -0.9398)
			(stroke
				(width 0)
				(type default)
			)
			(fill no)
			(layer "F.CrtYd")
		)
		(fp_rect
			(start -0.508 0.9398)
			(end 0.508 -0.9398)
			(stroke
				(width 0)
				(type default)
			)
			(fill no)
			(layer "F.Fab")
		)
		(pad "1" smd custom
			(at 0 -0.4445 90)
			(size 0.1397 0.1397)
			(layers "F.Cu" "F.Mask" "F.Paste")
			(net "P5VB")
			(options
				(clearance outline)
				(anchor circle)
			)
			(primitives
				(gr_poly
					(pts
						(arc
							(start -0.1778 -0.2794)
							(mid -0.249642 -0.249642)
							(end -0.2794 -0.1778)
						)
						(arc
							(start -0.2794 0.1778)
							(mid -0.249642 0.249642)
							(end -0.1778 0.2794)
						)
						(arc
							(start 0.1778 0.2794)
							(mid 0.249642 0.249642)
							(end 0.2794 0.1778)
						)
						(arc
							(start 0.2794 -0.1778)
							(mid 0.249642 -0.249642)
							(end 0.1778 -0.2794)
						)
					)
					(width 0)
					(fill yes)
				)
			)
		)
		(pad "2" smd custom
			(at 0 0.4445 90)
			(size 0.1397 0.1397)
			(layers "F.Cu" "F.Mask" "F.Paste")
			(net "DRIVE_ACT_5")
			(options
				(clearance outline)
				(anchor circle)
			)
			(primitives
				(gr_poly
					(pts
						(arc
							(start -0.1778 -0.2794)
							(mid -0.249642 -0.249642)
							(end -0.2794 -0.1778)
						)
						(arc
							(start -0.2794 0.1778)
							(mid -0.249642 0.249642)
							(end -0.1778 0.2794)
						)
						(arc
							(start 0.1778 0.2794)
							(mid 0.249642 0.249642)
							(end 0.2794 0.1778)
						)
						(arc
							(start 0.2794 -0.1778)
							(mid 0.249642 -0.249642)
							(end 0.1778 -0.2794)
						)
					)
					(width 0)
					(fill yes)
				)
			)
		)
	)
)
